(kicad_pcb
	(version 20260206)
	(generator "pcbnew")
	(generator_version "10.0")
	(general
		(thickness 1.6)
		(legacy_teardrops no)
	)
	(paper "A4")
	(title_block
		(title "04192023_DAF0TMB3IC0_F0TG_MB_C_brd_V02_OCP.brd")
		(comment 1 "Grand Teton / footprints 2718-2723 of 8354")
	)
	(layers
		(0 "F.Cu" signal "TOP")
		(4 "In1.Cu" signal "GND")
		(6 "In2.Cu" signal "IN1")
		(8 "In3.Cu" signal "GND1")
		(10 "In4.Cu" signal "IN2")
		(12 "In5.Cu" signal "GND2")
		(14 "In6.Cu" signal "IN3")
		(16 "In7.Cu" signal "GND3")
		(18 "In8.Cu" signal "VCC")
		(20 "In9.Cu" signal "VCC1")
		(22 "In10.Cu" signal "GND4")
		(24 "In11.Cu" signal "IN4")
		(26 "In12.Cu" signal "GND5")
		(28 "In13.Cu" signal "IN5")
		(30 "In14.Cu" signal "GND6")
		(32 "In15.Cu" signal "IN6")
		(34 "In16.Cu" signal "GND7")
		(2 "B.Cu" signal "BOTTOM")
		(9 "F.Adhes" user "F.Adhesive")
		(11 "B.Adhes" user "B.Adhesive")
		(13 "F.Paste" user "Package Geometry/Pastemask Top")
		(15 "B.Paste" user "Package Geometry/Pastemask Bottom")
		(5 "F.SilkS" user "Ref Des/Silkscreen Top")
		(7 "B.SilkS" user "Ref Des/Silkscreen Bottom")
		(1 "F.Mask" user "Board Geometry/Soldermask Top")
		(3 "B.Mask" user "Board Geometry/Soldermask Bottom")
		(17 "Dwgs.User" user "User.Drawings")
		(19 "Cmts.User" user "User.Comments")
		(21 "Eco1.User" user "User.Eco1")
		(23 "Eco2.User" user "User.Eco2")
		(25 "Edge.Cuts" user "Board Geometry/Outline")
		(27 "Margin" user)
		(31 "F.CrtYd" user "Package Geometry/Place Bound Top")
		(29 "B.CrtYd" user "Package Geometry/Place Bound Bottom")
		(35 "F.Fab" user "Ref Des/Assembly Top")
		(33 "B.Fab" user "Ref Des/Assembly Bottom")
	)
	(footprint ""
		(layer "F.Cu")
		(at 192.151 -133.568948 90)
		(property "Reference" "R173"
			(at 0 0 90)
			(layer "F.SilkS")
			(hide yes)
			(effects
				(font
					(size 1.27 1.27)
				)
			)
		)
		(property "Value" ""
			(at 0 0 90)
			(layer "F.Fab")
			(effects
				(font
					(size 1.27 1.27)
				)
			)
		)
		(duplicate_pad_numbers_are_jumpers no)
		(fp_line
			(start 0.7874 -0.4064)
			(end 0.7874 0.4064)
			(stroke
				(width 0.1524)
				(type default)
			)
			(layer "F.SilkS")
		)
		(fp_line
			(start -0.7874 -0.4064)
			(end 0.7874 -0.4064)
			(stroke
				(width 0.1524)
				(type default)
			)
			(layer "F.SilkS")
		)
		(fp_line
			(start 0.7874 0.4064)
			(end -0.7874 0.4064)
			(stroke
				(width 0.1524)
				(type default)
			)
			(layer "F.SilkS")
		)
		(fp_line
			(start -0.7874 0.4064)
			(end -0.7874 -0.4064)
			(stroke
				(width 0.1524)
				(type default)
			)
			(layer "F.SilkS")
		)
		(fp_line
			(start -0.12065 -0.305054)
			(end -0.12065 -0.2794)
			(stroke
				(width 0.1)
				(type default)
			)
			(layer "F.Fab")
		)
		(fp_line
			(start -0.67945 -0.305054)
			(end -0.12065 -0.305054)
			(stroke
				(width 0.1)
				(type default)
			)
			(layer "F.Fab")
		)
		(fp_line
			(start 0.67945 -0.3048)
			(end 0.67945 0.3048)
			(stroke
				(width 0.1)
				(type default)
			)
			(layer "F.Fab")
		)
		(fp_line
			(start 0.12065 -0.3048)
			(end 0.67945 -0.3048)
			(stroke
				(width 0.1)
				(type default)
			)
			(layer "F.Fab")
		)
		(fp_line
			(start 0.12065 -0.2794)
			(end 0.12065 -0.3048)
			(stroke
				(width 0.1)
				(type default)
			)
			(layer "F.Fab")
		)
		(fp_line
			(start -0.12065 -0.2794)
			(end 0.12065 -0.2794)
			(stroke
				(width 0.1)
				(type default)
			)
			(layer "F.Fab")
		)
		(fp_line
			(start 0.120396 0.2794)
			(end -0.12065 0.2794)
			(stroke
				(width 0.1)
				(type default)
			)
			(layer "F.Fab")
		)
		(fp_line
			(start -0.12065 0.2794)
			(end -0.12065 0.3048)
			(stroke
				(width 0.1)
				(type default)
			)
			(layer "F.Fab")
		)
		(fp_line
			(start 0.67945 0.3048)
			(end 0.120396 0.3048)
			(stroke
				(width 0.1)
				(type default)
			)
			(layer "F.Fab")
		)
		(fp_line
			(start 0.120396 0.3048)
			(end 0.120396 0.2794)
			(stroke
				(width 0.1)
				(type default)
			)
			(layer "F.Fab")
		)
		(fp_line
			(start -0.12065 0.3048)
			(end -0.67945 0.3048)
			(stroke
				(width 0.1)
				(type default)
			)
			(layer "F.Fab")
		)
		(fp_line
			(start -0.67945 0.3048)
			(end -0.67945 -0.305054)
			(stroke
				(width 0.1)
				(type default)
			)
			(layer "F.Fab")
		)
		(pad "1" smd circle
			(at -0.40005 0 90)
			(size 0 0)
			(layers "F.Cu" "F.Mask" "F.Paste")
			(net "FM_PLD_CPU1_PRSNT_HDT")
		)
		(pad "2" smd circle
			(at 0.40005 0 90)
			(size 0 0)
			(layers "F.Cu" "F.Mask" "F.Paste")
			(net "CPU1_HDT_BYPASS_SEL")
		)
	)
	(footprint ""
		(layer "F.Cu")
		(at 189.327028 -428.94758 -90)
		(property "Reference" "R9010"
			(at 0 0 270)
			(layer "F.SilkS")
			(hide yes)
			(effects
				(font
					(size 1.27 1.27)
				)
			)
		)
		(property "Value" ""
			(at 0 0 270)
			(layer "F.Fab")
			(effects
				(font
					(size 1.27 1.27)
				)
			)
		)
		(duplicate_pad_numbers_are_jumpers no)
		(fp_line
			(start -0.7874 0.4064)
			(end -0.7874 -0.4064)
			(stroke
				(width 0.1524)
				(type default)
			)
			(layer "F.SilkS")
		)
		(fp_line
			(start 0.7874 0.4064)
			(end -0.7874 0.4064)
			(stroke
				(width 0.1524)
				(type default)
			)
			(layer "F.SilkS")
		)
		(fp_line
			(start -0.7874 -0.4064)
			(end 0.7874 -0.4064)
			(stroke
				(width 0.1524)
				(type default)
			)
			(layer "F.SilkS")
		)
		(fp_line
			(start 0.7874 -0.4064)
			(end 0.7874 0.4064)
			(stroke
				(width 0.1524)
				(type default)
			)
			(layer "F.SilkS")
		)
		(fp_line
			(start -0.67945 0.3048)
			(end -0.67945 -0.305054)
			(stroke
				(width 0.1)
				(type default)
			)
			(layer "F.Fab")
		)
		(fp_line
			(start -0.12065 0.3048)
			(end -0.67945 0.3048)
			(stroke
				(width 0.1)
				(type default)
			)
			(layer "F.Fab")
		)
		(fp_line
			(start 0.120396 0.3048)
			(end 0.120396 0.2794)
			(stroke
				(width 0.1)
				(type default)
			)
			(layer "F.Fab")
		)
		(fp_line
			(start 0.67945 0.3048)
			(end 0.120396 0.3048)
			(stroke
				(width 0.1)
				(type default)
			)
			(layer "F.Fab")
		)
		(fp_line
			(start -0.12065 0.2794)
			(end -0.12065 0.3048)
			(stroke
				(width 0.1)
				(type default)
			)
			(layer "F.Fab")
		)
		(fp_line
			(start 0.120396 0.2794)
			(end -0.12065 0.2794)
			(stroke
				(width 0.1)
				(type default)
			)
			(layer "F.Fab")
		)
		(fp_line
			(start -0.12065 -0.2794)
			(end 0.12065 -0.2794)
			(stroke
				(width 0.1)
				(type default)
			)
			(layer "F.Fab")
		)
		(fp_line
			(start 0.12065 -0.2794)
			(end 0.12065 -0.3048)
			(stroke
				(width 0.1)
				(type default)
			)
			(layer "F.Fab")
		)
		(fp_line
			(start 0.12065 -0.3048)
			(end 0.67945 -0.3048)
			(stroke
				(width 0.1)
				(type default)
			)
			(layer "F.Fab")
		)
		(fp_line
			(start 0.67945 -0.3048)
			(end 0.67945 0.3048)
			(stroke
				(width 0.1)
				(type default)
			)
			(layer "F.Fab")
		)
		(fp_line
			(start -0.67945 -0.305054)
			(end -0.12065 -0.305054)
			(stroke
				(width 0.1)
				(type default)
			)
			(layer "F.Fab")
		)
		(fp_line
			(start -0.12065 -0.305054)
			(end -0.12065 -0.2794)
			(stroke
				(width 0.1)
				(type default)
			)
			(layer "F.Fab")
		)
		(pad "1" smd circle
			(at -0.40005 0 270)
			(size 0 0)
			(layers "F.Cu" "F.Mask" "F.Paste")
			(net "PRSNT_CABLE_SWB_B1_ISO_N")
		)
		(pad "2" smd circle
			(at 0.40005 0 270)
			(size 0 0)
			(layers "F.Cu" "F.Mask" "F.Paste")
			(net "PRSNT_CABLE_SWB_B1_ISO_R_N")
		)
	)
	(footprint ""
		(layer "F.Cu")
		(at 356.69601 -404.0124 -90)
		(property "Reference" "R1004"
			(at 0 0 270)
			(layer "F.SilkS")
			(hide yes)
			(effects
				(font
					(size 1.27 1.27)
				)
			)
		)
		(property "Value" ""
			(at 0 0 270)
			(layer "F.Fab")
			(effects
				(font
					(size 1.27 1.27)
				)
			)
		)
		(duplicate_pad_numbers_are_jumpers no)
		(fp_line
			(start -0.32512 0.175006)
			(end -0.32512 -0.175006)
			(stroke
				(width 0.1)
				(type default)
			)
			(layer "F.Fab")
		)
		(fp_line
			(start 0.32512 0.175006)
			(end -0.32512 0.175006)
			(stroke
				(width 0.1)
				(type default)
			)
			(layer "F.Fab")
		)
		(fp_line
			(start -0.32512 -0.175006)
			(end 0.32512 -0.175006)
			(stroke
				(width 0.1)
				(type default)
			)
			(layer "F.Fab")
		)
		(fp_line
			(start 0.32512 -0.175006)
			(end 0.32512 0.175006)
			(stroke
				(width 0.1)
				(type default)
			)
			(layer "F.Fab")
		)
		(pad "1" smd rect
			(at -0.2667 0 270)
			(size 0.3048 0.381)
			(layers "F.Cu" "F.Mask" "F.Paste")
			(net "RST_RT_CPU0_P1_PERST_N")
		)
		(pad "2" smd rect
			(at 0.2667 0 90)
			(size 0.3048 0.381)
			(layers "F.Cu" "F.Mask" "F.Paste")
			(net "RST_RT_CPU0_P1_PERST_R_N")
		)
	)
	(footprint ""
		(layer "F.Cu")
		(at 208.926684 -111.576866 180)
		(property "Reference" "R2262"
			(at 0 0 180)
			(layer "F.SilkS")
			(hide yes)
			(effects
				(font
					(size 1.27 1.27)
				)
			)
		)
		(property "Value" ""
			(at 0 0 180)
			(layer "F.Fab")
			(effects
				(font
					(size 1.27 1.27)
				)
			)
		)
		(duplicate_pad_numbers_are_jumpers no)
		(fp_line
			(start 0.7874 0.4064)
			(end -0.7874 0.4064)
			(stroke
				(width 0.1524)
				(type default)
			)
			(layer "F.SilkS")
		)
		(fp_line
			(start 0.7874 -0.4064)
			(end 0.7874 0.4064)
			(stroke
				(width 0.1524)
				(type default)
			)
			(layer "F.SilkS")
		)
		(fp_line
			(start -0.7874 0.4064)
			(end -0.7874 -0.4064)
			(stroke
				(width 0.1524)
				(type default)
			)
			(layer "F.SilkS")
		)
		(fp_line
			(start -0.7874 -0.4064)
			(end 0.7874 -0.4064)
			(stroke
				(width 0.1524)
				(type default)
			)
			(layer "F.SilkS")
		)
		(fp_line
			(start 0.67945 0.3048)
			(end 0.120396 0.3048)
			(stroke
				(width 0.1)
				(type default)
			)
			(layer "F.Fab")
		)
		(fp_line
			(start 0.67945 -0.3048)
			(end 0.67945 0.3048)
			(stroke
				(width 0.1)
				(type default)
			)
			(layer "F.Fab")
		)
		(fp_line
			(start 0.12065 -0.2794)
			(end 0.12065 -0.3048)
			(stroke
				(width 0.1)
				(type default)
			)
			(layer "F.Fab")
		)
		(fp_line
			(start 0.12065 -0.3048)
			(end 0.67945 -0.3048)
			(stroke
				(width 0.1)
				(type default)
			)
			(layer "F.Fab")
		)
		(fp_line
			(start 0.120396 0.3048)
			(end 0.120396 0.2794)
			(stroke
				(width 0.1)
				(type default)
			)
			(layer "F.Fab")
		)
		(fp_line
			(start 0.120396 0.2794)
			(end -0.12065 0.2794)
			(stroke
				(width 0.1)
				(type default)
			)
			(layer "F.Fab")
		)
		(fp_line
			(start -0.12065 0.3048)
			(end -0.67945 0.3048)
			(stroke
				(width 0.1)
				(type default)
			)
			(layer "F.Fab")
		)
		(fp_line
			(start -0.12065 0.2794)
			(end -0.12065 0.3048)
			(stroke
				(width 0.1)
				(type default)
			)
			(layer "F.Fab")
		)
		(fp_line
			(start -0.12065 -0.2794)
			(end 0.12065 -0.2794)
			(stroke
				(width 0.1)
				(type default)
			)
			(layer "F.Fab")
		)
		(fp_line
			(start -0.12065 -0.305054)
			(end -0.12065 -0.2794)
			(stroke
				(width 0.1)
				(type default)
			)
			(layer "F.Fab")
		)
		(fp_line
			(start -0.67945 0.3048)
			(end -0.67945 -0.305054)
			(stroke
				(width 0.1)
				(type default)
			)
			(layer "F.Fab")
		)
		(fp_line
			(start -0.67945 -0.305054)
			(end -0.12065 -0.305054)
			(stroke
				(width 0.1)
				(type default)
			)
			(layer "F.Fab")
		)
		(pad "1" smd circle
			(at -0.40005 0 180)
			(size 0 0)
			(layers "F.Cu" "F.Mask" "F.Paste")
			(net "FM_GPU_PWR_EN_R")
		)
		(pad "2" smd circle
			(at 0.40005 0 180)
			(size 0 0)
			(layers "F.Cu" "F.Mask" "F.Paste")
			(net "FM_GPU_PWR_EN")
		)
	)
	(footprint ""
		(layer "F.Cu")
		(at 146.104864 -194.567048 90)
		(property "Reference" "PR170"
			(at 0 0 90)
			(layer "F.SilkS")
			(hide yes)
			(effects
				(font
					(size 1.27 1.27)
				)
			)
		)
		(property "Value" ""
			(at 0 0 90)
			(layer "F.Fab")
			(effects
				(font
					(size 1.27 1.27)
				)
			)
		)
		(duplicate_pad_numbers_are_jumpers no)
		(fp_line
			(start 0.7874 -0.4064)
			(end 0.7874 0.4064)
			(stroke
				(width 0.1524)
				(type default)
			)
			(layer "F.SilkS")
		)
		(fp_line
			(start -0.7874 -0.4064)
			(end 0.7874 -0.4064)
			(stroke
				(width 0.1524)
				(type default)
			)
			(layer "F.SilkS")
		)
		(fp_line
			(start 0.7874 0.4064)
			(end -0.7874 0.4064)
			(stroke
				(width 0.1524)
				(type default)
			)
			(layer "F.SilkS")
		)
		(fp_line
			(start -0.7874 0.4064)
			(end -0.7874 -0.4064)
			(stroke
				(width 0.1524)
				(type default)
			)
			(layer "F.SilkS")
		)
		(fp_line
			(start -0.12065 -0.305054)
			(end -0.12065 -0.2794)
			(stroke
				(width 0.1)
				(type default)
			)
			(layer "F.Fab")
		)
		(fp_line
			(start -0.67945 -0.305054)
			(end -0.12065 -0.305054)
			(stroke
				(width 0.1)
				(type default)
			)
			(layer "F.Fab")
		)
		(fp_line
			(start 0.67945 -0.3048)
			(end 0.67945 0.3048)
			(stroke
				(width 0.1)
				(type default)
			)
			(layer "F.Fab")
		)
		(fp_line
			(start 0.12065 -0.3048)
			(end 0.67945 -0.3048)
			(stroke
				(width 0.1)
				(type default)
			)
			(layer "F.Fab")
		)
		(fp_line
			(start 0.12065 -0.2794)
			(end 0.12065 -0.3048)
			(stroke
				(width 0.1)
				(type default)
			)
			(layer "F.Fab")
		)
		(fp_line
			(start -0.12065 -0.2794)
			(end 0.12065 -0.2794)
			(stroke
				(width 0.1)
				(type default)
			)
			(layer "F.Fab")
		)
		(fp_line
			(start 0.120396 0.2794)
			(end -0.12065 0.2794)
			(stroke
				(width 0.1)
				(type default)
			)
			(layer "F.Fab")
		)
		(fp_line
			(start -0.12065 0.2794)
			(end -0.12065 0.3048)
			(stroke
				(width 0.1)
				(type default)
			)
			(layer "F.Fab")
		)
		(fp_line
			(start 0.67945 0.3048)
			(end 0.120396 0.3048)
			(stroke
				(width 0.1)
				(type default)
			)
			(layer "F.Fab")
		)
		(fp_line
			(start 0.120396 0.3048)
			(end 0.120396 0.2794)
			(stroke
				(width 0.1)
				(type default)
			)
			(layer "F.Fab")
		)
		(fp_line
			(start -0.12065 0.3048)
			(end -0.67945 0.3048)
			(stroke
				(width 0.1)
				(type default)
			)
			(layer "F.Fab")
		)
		(fp_line
			(start -0.67945 0.3048)
			(end -0.67945 -0.305054)
			(stroke
				(width 0.1)
				(type default)
			)
			(layer "F.Fab")
		)
		(pad "1" smd circle
			(at -0.40005 0 90)
			(size 0 0)
			(layers "F.Cu" "F.Mask" "F.Paste")
			(net "SVID_PVDDCR_CPU0_P1_SVD_R")
		)
		(pad "2" smd circle
			(at 0.40005 0 90)
			(size 0 0)
			(layers "F.Cu" "F.Mask" "F.Paste")
			(net "SVID_PVDDCR_CPU0_P1_SVD")
		)
	)
	(footprint ""
		(layer "F.Cu")
		(at 356.234746 -416.145218 90)
		(property "Reference" "Q134"
			(at -1.4224 -2.44348 90)
			(unlocked yes)
			(layer "F.SilkS")
			(effects
				(font
					(size 0.7874 0.5842)
					(thickness 0.1524)
				)
				(justify left)
			)
		)
		(property "Value" ""
			(at 0 0 90)
			(layer "F.Fab")
			(effects
				(font
					(size 1.27 1.27)
				)
			)
		)
		(duplicate_pad_numbers_are_jumpers no)
		(fp_line
			(start 1.332738 -1.100074)
			(end 1.332738 1.100074)
			(stroke
				(width 0.1524)
				(type default)
			)
			(layer "F.SilkS")
		)
		(fp_line
			(start 0.4826 -1.100074)
			(end 1.332738 -1.100074)
			(stroke
				(width 0.1524)
				(type default)
			)
			(layer "F.SilkS")
		)
		(fp_line
			(start -0.4826 -1.100074)
			(end 0 -0.541274)
			(stroke
				(width 0.1524)
				(type default)
			)
			(layer "F.SilkS")
		)
		(fp_line
			(start -1.332738 -1.100074)
			(end -0.4826 -1.100074)
			(stroke
				(width 0.1524)
				(type default)
			)
			(layer "F.SilkS")
		)
		(fp_line
			(start 0 -0.541274)
			(end 0.4826 -1.100074)
			(stroke
				(width 0.1524)
				(type default)
			)
			(layer "F.SilkS")
		)
		(fp_line
			(start 1.332738 1.100074)
			(end -1.332738 1.100074)
			(stroke
				(width 0.1524)
				(type default)
			)
			(layer "F.SilkS")
		)
		(fp_line
			(start -1.332738 1.100074)
			(end -1.332738 -1.100074)
			(stroke
				(width 0.1524)
				(type default)
			)
			(layer "F.SilkS")
		)
		(fp_poly
			(pts
				(xy -1.489456 -1.189482) (xy -2.23393 -1.43764) (xy -1.737614 -1.933956)
			)
			(stroke
				(width 0)
				(type default)
			)
			(fill yes)
			(layer "F.SilkS")
		)
		(fp_line
			(start 0.674878 -1.100074)
			(end 0.674878 1.100074)
			(stroke
				(width 0.1)
				(type default)
			)
			(layer "F.Fab")
		)
		(fp_line
			(start -0.674878 -1.100074)
			(end 0.674878 -1.100074)
			(stroke
				(width 0.1)
				(type default)
			)
			(layer "F.Fab")
		)
		(fp_line
			(start 0.674878 1.100074)
			(end -0.674878 1.100074)
			(stroke
				(width 0.1)
				(type default)
			)
			(layer "F.Fab")
		)
		(fp_line
			(start -0.674878 1.100074)
			(end -0.674878 -1.100074)
			(stroke
				(width 0.1)
				(type default)
			)
			(layer "F.Fab")
		)
		(fp_poly
			(pts
				(xy -2.2352 -0.298958) (xy -2.2352 -1.001014) (xy -1.533144 -0.649986)
			)
			(stroke
				(width 0)
				(type default)
			)
			(fill yes)
			(layer "F.Fab")
		)
		(pad "1" smd rect
			(at -0.94996 -0.649986 180)
			(size 0.4318 0.508)
			(layers "F.Cu" "F.Mask" "F.Paste")
			(net "GND")
		)
		(pad "2" smd rect
			(at -0.94996 0 180)
			(size 0.4318 0.508)
			(layers "F.Cu" "F.Mask" "F.Paste")
			(net "PRSNT_CABLE_GPU_A1_N")
		)
		(pad "3" smd rect
			(at -0.94996 0.649986 180)
			(size 0.4318 0.508)
			(layers "F.Cu" "F.Mask" "F.Paste")
			(net "PRSNT_CABLE_GPU_A1_ISO_N")
		)
		(pad "4" smd rect
			(at 0.94996 0.649986 180)
			(size 0.4318 0.508)
			(layers "F.Cu" "F.Mask" "F.Paste")
			(net "GND")
		)
		(pad "5" smd rect
			(at 0.94996 0 180)
			(size 0.4318 0.508)
			(layers "F.Cu" "F.Mask" "F.Paste")
			(net "PRSNT_CABLE_GPU_A1")
		)
		(pad "6" smd rect
			(at 0.94996 -0.649986 180)
			(size 0.4318 0.508)
			(layers "F.Cu" "F.Mask" "F.Paste")
			(net "PRSNT_CABLE_GPU_A1")
		)
	)
)
